# T6G (Grand Teton) — schematic netlist excerpt (pin names and nets, part order shuffled) for the footprints in the layout excerpt that follows; sources: Cadence DE-HDL packaged netlist, KiCad conversion of 04192023_DAF0TMB3IC0_F0TG_MB_C_brd_V02_OCP.brd

R6250  Q_RES  4.7K 1% CHIP  pkg 0402LF  page 271 : A = GND ; B = HSC_TYPE_ADC_A1
C6017  Q_CAP  0.1UF 25V 10% X7R  pkg 0402  page 180 : A = USB3_CPU0_BMC_RX_HUB2_DP ; B = USB3_CPU0_BMC_RX_HUB_C_DP

(kicad_pcb
	(version 20260206)
	(generator "pcbnew")
	(generator_version "10.0")
	(general
		(thickness 1.6)
		(legacy_teardrops no)
	)
	(paper "A4")
	(title_block
		(title "04192023_DAF0TMB3IC0_F0TG_MB_C_brd_V02_OCP.brd")
		(comment 1 "Grand Teton / footprints 1953-1954 of 8354")
	)
	(layers
		(0 "F.Cu" signal "TOP")
		(4 "In1.Cu" signal "GND")
		(6 "In2.Cu" signal "IN1")
		(8 "In3.Cu" signal "GND1")
		(10 "In4.Cu" signal "IN2")
		(12 "In5.Cu" signal "GND2")
		(14 "In6.Cu" signal "IN3")
		(16 "In7.Cu" signal "GND3")
		(18 "In8.Cu" signal "VCC")
		(20 "In9.Cu" signal "VCC1")
		(22 "In10.Cu" signal "GND4")
		(24 "In11.Cu" signal "IN4")
		(26 "In12.Cu" signal "GND5")
		(28 "In13.Cu" signal "IN5")
		(30 "In14.Cu" signal "GND6")
		(32 "In15.Cu" signal "IN6")
		(34 "In16.Cu" signal "GND7")
		(2 "B.Cu" signal "BOTTOM")
		(9 "F.Adhes" user "F.Adhesive")
		(11 "B.Adhes" user "B.Adhesive")
		(13 "F.Paste" user "Package Geometry/Pastemask Top")
		(15 "B.Paste" user "Package Geometry/Pastemask Bottom")
		(5 "F.SilkS" user "Ref Des/Silkscreen Top")
		(7 "B.SilkS" user "Ref Des/Silkscreen Bottom")
		(1 "F.Mask" user "Board Geometry/Soldermask Top")
		(3 "B.Mask" user "Board Geometry/Soldermask Bottom")
		(17 "Dwgs.User" user "User.Drawings")
		(19 "Cmts.User" user "User.Comments")
		(21 "Eco1.User" user "User.Eco1")
		(23 "Eco2.User" user "User.Eco2")
		(25 "Edge.Cuts" user "Board Geometry/Outline")
		(27 "Margin" user)
		(31 "F.CrtYd" user "Package Geometry/Place Bound Top")
		(29 "B.CrtYd" user "Package Geometry/Place Bound Bottom")
		(35 "F.Fab" user "Ref Des/Assembly Top")
		(33 "B.Fab" user "Ref Des/Assembly Bottom")
	)
	(footprint ""
		(layer "F.Cu")
		(at 426.673264 -423.621962 90)
		(property "Reference" "R6250"
			(at 0 0 90)
			(layer "F.SilkS")
			(hide yes)
			(effects
				(font
					(size 1.27 1.27)
				)
			)
		)
		(property "Value" ""
			(at 0 0 90)
			(layer "F.Fab")
			(effects
				(font
					(size 1.27 1.27)
				)
			)
		)
		(duplicate_pad_numbers_are_jumpers no)
		(fp_line
			(start 0.7874 -0.4064)
			(end 0.7874 0.4064)
			(stroke
				(width 0.1524)
				(type default)
			)
			(layer "F.SilkS")
		)
		(fp_line
			(start -0.7874 -0.4064)
			(end 0.7874 -0.4064)
			(stroke
				(width 0.1524)
				(type default)
			)
			(layer "F.SilkS")
		)
		(fp_line
			(start 0.7874 0.4064)
			(end -0.7874 0.4064)
			(stroke
				(width 0.1524)
				(type default)
			)
			(layer "F.SilkS")
		)
		(fp_line
			(start -0.7874 0.4064)
			(end -0.7874 -0.4064)
			(stroke
				(width 0.1524)
				(type default)
			)
			(layer "F.SilkS")
		)
		(fp_line
			(start -0.12065 -0.305054)
			(end -0.12065 -0.2794)
			(stroke
				(width 0.1)
				(type default)
			)
			(layer "F.Fab")
		)
		(fp_line
			(start -0.67945 -0.305054)
			(end -0.12065 -0.305054)
			(stroke
				(width 0.1)
				(type default)
			)
			(layer "F.Fab")
		)
		(fp_line
			(start 0.67945 -0.3048)
			(end 0.67945 0.3048)
			(stroke
				(width 0.1)
				(type default)
			)
			(layer "F.Fab")
		)
		(fp_line
			(start 0.12065 -0.3048)
			(end 0.67945 -0.3048)
			(stroke
				(width 0.1)
				(type default)
			)
			(layer "F.Fab")
		)
		(fp_line
			(start 0.12065 -0.2794)
			(end 0.12065 -0.3048)
			(stroke
				(width 0.1)
				(type default)
			)
			(layer "F.Fab")
		)
		(fp_line
			(start -0.12065 -0.2794)
			(end 0.12065 -0.2794)
			(stroke
				(width 0.1)
				(type default)
			)
			(layer "F.Fab")
		)
		(fp_line
			(start 0.120396 0.2794)
			(end -0.12065 0.2794)
			(stroke
				(width 0.1)
				(type default)
			)
			(layer "F.Fab")
		)
		(fp_line
			(start -0.12065 0.2794)
			(end -0.12065 0.3048)
			(stroke
				(width 0.1)
				(type default)
			)
			(layer "F.Fab")
		)
		(fp_line
			(start 0.67945 0.3048)
			(end 0.120396 0.3048)
			(stroke
				(width 0.1)
				(type default)
			)
			(layer "F.Fab")
		)
		(fp_line
			(start 0.120396 0.3048)
			(end 0.120396 0.2794)
			(stroke
				(width 0.1)
				(type default)
			)
			(layer "F.Fab")
		)
		(fp_line
			(start -0.12065 0.3048)
			(end -0.67945 0.3048)
			(stroke
				(width 0.1)
				(type default)
			)
			(layer "F.Fab")
		)
		(fp_line
			(start -0.67945 0.3048)
			(end -0.67945 -0.305054)
			(stroke
				(width 0.1)
				(type default)
			)
			(layer "F.Fab")
		)
		(pad "1" smd circle
			(at -0.40005 0 90)
			(size 0 0)
			(layers "F.Cu" "F.Mask" "F.Paste")
			(net "GND")
		)
		(pad "2" smd circle
			(at 0.40005 0 90)
			(size 0 0)
			(layers "F.Cu" "F.Mask" "F.Paste")
			(net "HSC_TYPE_ADC_A1")
		)
	)
	(footprint ""
		(layer "F.Cu")
		(at 141.29512 -30.82671 90)
		(property "Reference" "C6017"
			(at 0 0 90)
			(layer "F.SilkS")
			(hide yes)
			(effects
				(font
					(size 1.27 1.27)
				)
			)
		)
		(property "Value" ""
			(at 0 0 90)
			(layer "F.Fab")
			(effects
				(font
					(size 1.27 1.27)
				)
			)
		)
		(duplicate_pad_numbers_are_jumpers no)
		(fp_line
			(start 0.7874 -0.4064)
			(end 0.7874 0.4064)
			(stroke
				(width 0.1524)
				(type default)
			)
			(layer "F.SilkS")
		)
		(fp_line
			(start -0.7874 -0.4064)
			(end 0.7874 -0.4064)
			(stroke
				(width 0.1524)
				(type default)
			)
			(layer "F.SilkS")
		)
		(fp_line
			(start 0.7874 0.4064)
			(end -0.7874 0.4064)
			(stroke
				(width 0.1524)
				(type default)
			)
			(layer "F.SilkS")
		)
		(fp_line
			(start -0.7874 0.4064)
			(end -0.7874 -0.4064)
			(stroke
				(width 0.1524)
				(type default)
			)
			(layer "F.SilkS")
		)
		(fp_line
			(start 0.6858 -0.3048)
			(end 0.6858 0.3048)
			(stroke
				(width 0.1)
				(type default)
			)
			(layer "F.Fab")
		)
		(fp_line
			(start 0.1016 -0.3048)
			(end 0.6858 -0.3048)
			(stroke
				(width 0.1)
				(type default)
			)
			(layer "F.Fab")
		)
		(fp_line
			(start -0.1016 -0.3048)
			(end -0.1016 -0.2794)
			(stroke
				(width 0.1)
				(type default)
			)
			(layer "F.Fab")
		)
		(fp_line
			(start -0.6858 -0.3048)
			(end -0.1016 -0.3048)
			(stroke
				(width 0.1)
				(type default)
			)
			(layer "F.Fab")
		)
		(fp_line
			(start 0.1016 -0.2794)
			(end 0.1016 -0.3048)
			(stroke
				(width 0.1)
				(type default)
			)
			(layer "F.Fab")
		)
		(fp_line
			(start -0.1016 -0.2794)
			(end 0.1016 -0.2794)
			(stroke
				(width 0.1)
				(type default)
			)
			(layer "F.Fab")
		)
		(fp_line
			(start 0.1016 0.2794)
			(end -0.1016 0.2794)
			(stroke
				(width 0.1)
				(type default)
			)
			(layer "F.Fab")
		)
		(fp_line
			(start -0.1016 0.2794)
			(end -0.1016 0.3048)
			(stroke
				(width 0.1)
				(type default)
			)
			(layer "F.Fab")
		)
		(fp_line
			(start 0.6858 0.3048)
			(end 0.1016 0.3048)
			(stroke
				(width 0.1)
				(type default)
			)
			(layer "F.Fab")
		)
		(fp_line
			(start 0.1016 0.3048)
			(end 0.1016 0.2794)
			(stroke
				(width 0.1)
				(type default)
			)
			(layer "F.Fab")
		)
		(fp_line
			(start -0.1016 0.3048)
			(end -0.6858 0.3048)
			(stroke
				(width 0.1)
				(type default)
			)
			(layer "F.Fab")
		)
		(fp_line
			(start -0.6858 0.3048)
			(end -0.6858 -0.3048)
			(stroke
				(width 0.1)
				(type default)
			)
			(layer "F.Fab")
		)
		(pad "1" smd rect
			(at -0.40005 0 270)
			(size 0.4572 0.508)
			(layers "F.Cu" "F.Mask" "F.Paste")
			(net "USB3_CPU0_BMC_RX_HUB2_DP")
		)
		(pad "2" smd rect
			(at 0.40005 0 270)
			(size 0.4572 0.508)
			(layers "F.Cu" "F.Mask" "F.Paste")
			(net "USB3_CPU0_BMC_RX_HUB_C_DP")
		)
	)
)
